FILE_TYPE = MACRO_DRAWING;
SET COLOR_WIRE YELLOW;
SET COLOR_PROP ORANGE;
SET COLOR_DOT WHITE;
SET COLOR_ARC YELLOW;
SET COLOR_BODY GREEN;
SET COLOR_NOTE PURPLE;
SET PROP_DISPLAY VALUE;
SET PAGE_NUMBER P191;
FORCEADD OFFPAGE..1
(-2900 4150);
FORCEPROP 2 LAST $XR0 223 
J 0
(-3152 4150);
DISPLAY 0.638298 (-3152 4150);
PAINT MONO (-3152 4150);
FORCEPROP 2 LAST CDS_LIB standard
J 0
(-2900 4150);
PAINT MONO (-2900 4150);
DISPLAY INVISIBLE (-2900 4150);
FORCEPROP 1 LAST OFFPAGE TRUE
J 0
(-2575 4025);
DISPLAY 0.872340 (-2575 4025);
PAINT GREEN (-2575 4025);
DISPLAY INVISIBLE (-2575 4025);
FORCEPROP 1 LAST COMMENT_BODY TRUE
J 0
(-2775 4050);
DISPLAY 0.872340 (-2775 4050);
PAINT GREEN (-2775 4050);
DISPLAY INVISIBLE (-2775 4050);
FORCEPROP 2 LAST PATH I1
J 0
(-3175 4200);
DISPLAY 1.021277 (-3175 4200);
DISPLAY INVISIBLE (-3175 4200);
FORCEADD OFFPAGE..1
(-2900 975);
FORCEPROP 2 LAST $XR0 182 
J 0
(-3152 975);
DISPLAY 0.638298 (-3152 975);
PAINT MONO (-3152 975);
FORCEPROP 2 LAST CDS_LIB standard
J 0
(-2900 975);
PAINT MONO (-2900 975);
DISPLAY INVISIBLE (-2900 975);
FORCEPROP 1 LAST OFFPAGE TRUE
J 0
(-2575 850);
DISPLAY 0.872340 (-2575 850);
PAINT GREEN (-2575 850);
DISPLAY INVISIBLE (-2575 850);
FORCEPROP 1 LAST COMMENT_BODY TRUE
J 0
(-2775 875);
DISPLAY 0.872340 (-2775 875);
PAINT GREEN (-2775 875);
DISPLAY INVISIBLE (-2775 875);
FORCEPROP 2 LAST PATH I10
J 0
(-3150 1025);
DISPLAY 1.021277 (-3150 1025);
DISPLAY INVISIBLE (-3150 1025);
FORCEADD Q_RES..1
(-1675 975);
FORCEPROP 1 LAST PART_NUMBER CS00002JB13
J 0
(-1775 1050);
DISPLAY 0.510638 (-1775 1050);
DISPLAY INVISIBLE (-1775 1050);
FORCEPROP 1 LAST MATERIAL CHIP
J 0
(-1425 975);
DISPLAY 0.638298 (-1425 975);
FORCEPROP 1 LAST PACK_TYPE 0402LF
J 0
(-1775 1100);
DISPLAY 0.510638 (-1775 1100);
FORCEPROP 1 LAST WATTAGE 1/16W
J 2
(-1500 1100);
DISPLAY 0.510638 (-1500 1100);
FORCEPROP 1 LAST TOLERANCE 5%
J 0
(-1500 975);
DISPLAY 0.638298 (-1500 975);
FORCEPROP 1 LAST VALUE 0
J 2
(-1525 975);
DISPLAY 0.638298 (-1525 975);
FORCEPROP 1 LAST $LOCATION R1247
J 0
(-1875 975);
DISPLAY 0.638298 (-1875 975);
FORCEPROP 1 LASTPIN (-1775 975) $PN 1
J 0
(-1763 987);
DISPLAY 0.787234 (-1763 987);
FORCEPROP 1 LASTPIN (-1575 975) $PN 2
J 0
(-1613 987);
DISPLAY 0.787234 (-1613 987);
FORCEPROP 2 LAST CDS_LIB pure_quanta
J 0
(-1675 975);
PAINT MONO (-1675 975);
DISPLAY INVISIBLE (-1675 975);
FORCEPROP 1 LAST PATH I14
J 0
(-1725 1125);
DISPLAY 0.978723 (-1725 1125);
PAINT WHITE (-1725 1125);
DISPLAY INVISIBLE (-1725 1125);
FORCEPROP 1 LAST $LOCATION R1247
J 0
(-1725 1175);
DISPLAY 1.021277 (-1725 1175);
DISPLAY INVISIBLE (-1725 1175);
FORCEPROP 2 LAST CDS_LOCATION R1247
J 0
(-1725 1175);
DISPLAY 1.021277 (-1725 1175);
DISPLAY INVISIBLE (-1725 1175);
FORCEPROP 2 LAST $SEC 1
J 0
(-1725 1175);
DISPLAY 0.680851 (-1725 1175);
PAINT MONO (-1725 1175);
DISPLAY INVISIBLE (-1725 1175);
FORCEPROP 2 LAST CDS_SEC 1
J 0
(-1725 1175);
DISPLAY 1.021277 (-1725 1175);
DISPLAY INVISIBLE (-1725 1175);
FORCEADD Q_RES..1
(-1675 4150);
FORCEPROP 1 LAST PART_NUMBER CS00002JB13
J 0
(-1750 4225);
DISPLAY 0.510638 (-1750 4225);
DISPLAY INVISIBLE (-1750 4225);
FORCEPROP 1 LAST WATTAGE 1/16W
J 2
(-1475 4275);
DISPLAY 0.510638 (-1475 4275);
FORCEPROP 1 LAST MATERIAL CHIP
J 0
(-1750 4275);
DISPLAY 0.510638 (-1750 4275);
FORCEPROP 1 LAST TOLERANCE 5%
J 0
(-1500 4150);
DISPLAY 0.638298 (-1500 4150);
FORCEPROP 1 LAST PACK_TYPE 0402LF
J 0
(-1425 4150);
DISPLAY 0.638298 (-1425 4150);
FORCEPROP 1 LAST VALUE 0
J 2
(-1525 4150);
DISPLAY 0.638298 (-1525 4150);
FORCEPROP 1 LAST $LOCATION R1249
J 0
(-1900 4150);
DISPLAY 0.638298 (-1900 4150);
FORCEPROP 1 LASTPIN (-1775 4150) $PN 1
J 0
(-1763 4162);
DISPLAY 0.787234 (-1763 4162);
FORCEPROP 1 LASTPIN (-1575 4150) $PN 2
J 0
(-1613 4162);
DISPLAY 0.787234 (-1613 4162);
FORCEPROP 2 LAST CDS_LIB pure_quanta
J 0
(-1675 4150);
PAINT MONO (-1675 4150);
DISPLAY INVISIBLE (-1675 4150);
FORCEPROP 1 LAST PATH I2
J 0
(-1725 4300);
DISPLAY 0.978723 (-1725 4300);
PAINT WHITE (-1725 4300);
DISPLAY INVISIBLE (-1725 4300);
FORCEPROP 1 LAST $LOCATION R1249
J 0
(-1725 4350);
DISPLAY 1.021277 (-1725 4350);
DISPLAY INVISIBLE (-1725 4350);
FORCEPROP 2 LAST CDS_LOCATION R1249
J 0
(-1725 4350);
DISPLAY 1.021277 (-1725 4350);
DISPLAY INVISIBLE (-1725 4350);
FORCEPROP 2 LAST $SEC 1
J 0
(-1725 4350);
DISPLAY 0.680851 (-1725 4350);
PAINT MONO (-1725 4350);
DISPLAY INVISIBLE (-1725 4350);
FORCEPROP 2 LAST CDS_SEC 1
J 0
(-1725 4350);
DISPLAY 1.021277 (-1725 4350);
DISPLAY INVISIBLE (-1725 4350);
FORCEADD OFFPAGE..2
(1000 975);
FORCEPROP 2 LAST $XR1 239 
J 0
(1309 975);
DISPLAY 0.638298 (1309 975);
PAINT MONO (1309 975);
FORCEPROP 2 LAST $XR0 131 
J 0
(1189 975);
DISPLAY 0.638298 (1189 975);
PAINT MONO (1189 975);
FORCEPROP 2 LAST CDS_LIB standard
J 0
(1000 975);
DISPLAY INVISIBLE (1000 975);
FORCEPROP 1 LAST OFFPAGE TRUE
J 0
(1325 850);
DISPLAY 0.872340 (1325 850);
PAINT GREEN (1325 850);
DISPLAY INVISIBLE (1325 850);
FORCEPROP 1 LAST COMMENT_BODY TRUE
J 0
(955 880);
DISPLAY 0.872340 (955 880);
PAINT GREEN (955 880);
DISPLAY INVISIBLE (955 880);
FORCEPROP 2 LAST PATH I22
J 0
(1200 1025);
DISPLAY 1.021277 (1200 1025);
DISPLAY INVISIBLE (1200 1025);
FORCEADD OFFPAGE..1
(-2900 3125);
FORCEPROP 2 LAST $XR0 183 
J 0
(-3152 3125);
DISPLAY 0.638298 (-3152 3125);
PAINT MONO (-3152 3125);
FORCEPROP 2 LAST CDS_LIB standard
J 0
(-2900 3125);
PAINT MONO (-2900 3125);
DISPLAY INVISIBLE (-2900 3125);
FORCEPROP 1 LAST OFFPAGE TRUE
J 0
(-2575 3000);
DISPLAY 0.872340 (-2575 3000);
PAINT GREEN (-2575 3000);
DISPLAY INVISIBLE (-2575 3000);
FORCEPROP 1 LAST COMMENT_BODY TRUE
J 0
(-2775 3025);
DISPLAY 0.872340 (-2775 3025);
PAINT GREEN (-2775 3025);
DISPLAY INVISIBLE (-2775 3025);
FORCEPROP 2 LAST PATH I28
J 0
(-3150 3175);
DISPLAY 1.021277 (-3150 3175);
DISPLAY INVISIBLE (-3150 3175);
FORCEADD Q_RES..1
(-1750 3125);
FORCEPROP 1 LAST PART_NUMBER CS03322FB03
J 0
(-1825 3200);
DISPLAY 0.510638 (-1825 3200);
DISPLAY INVISIBLE (-1825 3200);
FORCEPROP 1 LAST PACK_TYPE 0402LF
J 0
(-1825 3250);
DISPLAY 0.510638 (-1825 3250);
FORCEPROP 1 LAST MATERIAL CHIP
J 0
(-1500 3125);
DISPLAY 0.638298 (-1500 3125);
FORCEPROP 1 LAST VALUE 33.2
J 2
(-1600 3125);
DISPLAY 0.638298 (-1600 3125);
FORCEPROP 1 LAST WATTAGE 1/16W
J 2
(-1525 3250);
DISPLAY 0.510638 (-1525 3250);
FORCEPROP 1 LAST TOLERANCE 1%
J 0
(-1575 3125);
DISPLAY 0.638298 (-1575 3125);
FORCEPROP 1 LAST $LOCATION R1263
J 0
(-1975 3125);
DISPLAY 0.638298 (-1975 3125);
FORCEPROP 1 LASTPIN (-1850 3125) $PN 1
J 0
(-1838 3137);
DISPLAY 0.787234 (-1838 3137);
FORCEPROP 1 LASTPIN (-1650 3125) $PN 2
J 0
(-1688 3137);
DISPLAY 0.787234 (-1688 3137);
FORCEPROP 2 LAST CDS_LIB pure_quanta
J 0
(-1750 3125);
PAINT MONO (-1750 3125);
DISPLAY INVISIBLE (-1750 3125);
FORCEPROP 1 LAST PATH I29
J 0
(-1800 3275);
DISPLAY 0.978723 (-1800 3275);
PAINT WHITE (-1800 3275);
DISPLAY INVISIBLE (-1800 3275);
FORCEPROP 2 LAST CDS_LOCATION R1263
J 0
(-1800 3325);
DISPLAY 1.021277 (-1800 3325);
DISPLAY INVISIBLE (-1800 3325);
FORCEPROP 2 LAST $SEC 1
J 0
(-1800 3325);
DISPLAY 0.680851 (-1800 3325);
PAINT MONO (-1800 3325);
DISPLAY INVISIBLE (-1800 3325);
FORCEPROP 2 LAST CDS_SEC 1
J 0
(-1800 3325);
DISPLAY 1.021277 (-1800 3325);
DISPLAY INVISIBLE (-1800 3325);
FORCEADD OFFPAGE..2
(-250 3125);
FORCEPROP 2 LAST $XR0 215 
J 0
(-61 3125);
DISPLAY 0.638298 (-61 3125);
PAINT MONO (-61 3125);
FORCEPROP 2 LAST CDS_LIB standard
J 0
(-250 3125);
PAINT MONO (-250 3125);
DISPLAY INVISIBLE (-250 3125);
FORCEPROP 1 LAST OFFPAGE TRUE
J 0
(75 3000);
DISPLAY 0.872340 (75 3000);
PAINT GREEN (75 3000);
DISPLAY INVISIBLE (75 3000);
FORCEPROP 1 LAST COMMENT_BODY TRUE
J 0
(-295 3030);
DISPLAY 0.872340 (-295 3030);
PAINT GREEN (-295 3030);
DISPLAY INVISIBLE (-295 3030);
FORCEPROP 2 LAST PATH I30
J 0
(-50 3175);
DISPLAY 1.021277 (-50 3175);
DISPLAY INVISIBLE (-50 3175);
FORCEADD UNIVERSAL_POWER..1
(-2775 3700);
FORCEPROP 3 LASTPIN (-2775 3650) SIG_NAME P3V3_AUX\g
J 0
(-2765 3660);
DISPLAY 0.659574 (-2765 3660);
PAINT MONO (-2765 3660);
DISPLAY INVISIBLE (-2765 3660);
FORCEPROP 1 LAST HDL_POWER P3V3_AUX
J 1
(-2775 3750);
DISPLAY 0.872340 (-2775 3750);
PAINT GREEN (-2775 3750);
FORCEPROP 2 LAST CDS_LIB logical_power
J 0
(-2775 3700);
PAINT MONO (-2775 3700);
DISPLAY INVISIBLE (-2775 3700);
FORCEPROP 1 LAST PATH I34
J 0
(-2725 3725);
DISPLAY 0.872340 (-2725 3725);
PAINT AQUA (-2725 3725);
DISPLAY INVISIBLE (-2725 3725);
FORCEADD Q_RES..2
(-2775 3450);
FORCEPROP 1 LAST PART_NUMBER CS31002FB08
J 0
(-2735 3325);
DISPLAY 0.510638 (-2735 3325);
DISPLAY INVISIBLE (-2735 3325);
FORCEPROP 1 LAST MATERIAL CHIP
J 0
(-2735 3375);
DISPLAY 0.510638 (-2735 3375);
FORCEPROP 1 LAST VALUE 10K
J 0
(-2730 3525);
DISPLAY 0.510638 (-2730 3525);
FORCEPROP 1 LAST PACK_TYPE 0402LF
J 0
(-2735 3275);
DISPLAY 0.510638 (-2735 3275);
FORCEPROP 1 LAST WATTAGE 1/16W
J 0
(-2735 3425);
DISPLAY 0.510638 (-2735 3425);
FORCEPROP 1 LAST TOLERANCE 1%
J 0
(-2730 3475);
DISPLAY 0.510638 (-2730 3475);
FORCEPROP 1 LAST $LOCATION R1820
J 0
(-2730 3575);
DISPLAY 0.978723 (-2730 3575);
FORCEPROP 1 LASTPIN (-2775 3550) $PN 1
J 0
(-2770 3512);
DISPLAY 0.787234 (-2770 3512);
FORCEPROP 1 LASTPIN (-2775 3350) $PN 2
J 0
(-2770 3360);
DISPLAY 0.787234 (-2770 3360);
FORCEPROP 2 LAST CDS_LIB pure_quanta
J 0
(-2775 3450);
PAINT MONO (-2775 3450);
DISPLAY INVISIBLE (-2775 3450);
FORCEPROP 1 LAST PATH I35
J 0
(-2725 3625);
DISPLAY 0.978723 (-2725 3625);
PAINT WHITE (-2725 3625);
DISPLAY INVISIBLE (-2725 3625);
FORCEPROP 2 LAST CDS_LOCATION R1820
J 0
(-2725 3675);
DISPLAY 1.021277 (-2725 3675);
DISPLAY INVISIBLE (-2725 3675);
FORCEPROP 2 LAST $SEC 1
J 0
(-2725 3675);
DISPLAY 0.680851 (-2725 3675);
PAINT MONO (-2725 3675);
DISPLAY INVISIBLE (-2725 3675);
FORCEPROP 2 LAST CDS_SEC 1
J 0
(-2725 3675);
DISPLAY 1.021277 (-2725 3675);
DISPLAY INVISIBLE (-2725 3675);
FORCEADD UNIVERSAL_POWER..1
(175 4650);
FORCEPROP 3 LASTPIN (175 4600) SIG_NAME P1V05_PCH_AUX\g
J 0
(185 4610);
DISPLAY 0.659574 (185 4610);
PAINT MONO (185 4610);
DISPLAY INVISIBLE (185 4610);
FORCEPROP 1 LAST HDL_POWER P1V05_PCH_AUX
J 1
(175 4700);
DISPLAY 0.872340 (175 4700);
PAINT GREEN (175 4700);
FORCEPROP 2 LAST CDS_LIB logical_power
J 0
(175 4650);
DISPLAY INVISIBLE (175 4650);
FORCEPROP 1 LAST PATH I37
J 0
(225 4675);
DISPLAY 0.872340 (225 4675);
PAINT AQUA (225 4675);
DISPLAY INVISIBLE (225 4675);
FORCEADD Q_RES..2
(175 4400);
FORCEPROP 1 LAST PART_NUMBER CS07502FB04
J 0
(215 4275);
DISPLAY 0.510638 (215 4275);
DISPLAY INVISIBLE (215 4275);
FORCEPROP 1 LAST TOLERANCE 1%
J 0
(220 4425);
DISPLAY 0.510638 (220 4425);
FORCEPROP 1 LAST VALUE 75
J 0
(220 4475);
DISPLAY 0.510638 (220 4475);
FORCEPROP 1 LAST PACK_TYPE 0402LF
J 0
(215 4225);
DISPLAY 0.510638 (215 4225);
FORCEPROP 1 LAST MATERIAL CHIP
J 0
(215 4325);
DISPLAY 0.510638 (215 4325);
FORCEPROP 1 LAST WATTAGE 1/16W
J 0
(215 4375);
DISPLAY 0.510638 (215 4375);
FORCEPROP 1 LAST LOCATION R1266
J 0
(220 4525);
DISPLAY 0.638298 (220 4525);
FORCEPROP 1 LASTPIN (175 4500) $PN 1
J 0
(180 4462);
DISPLAY 0.787234 (180 4462);
PAINT MONO (180 4462);
FORCEPROP 1 LASTPIN (175 4300) $PN 2
J 0
(180 4310);
DISPLAY 0.787234 (180 4310);
PAINT MONO (180 4310);
FORCEPROP 2 LAST CDS_LIB pure_quanta
J 0
(175 4400);
DISPLAY INVISIBLE (175 4400);
FORCEPROP 1 LAST PATH I38
J 0
(225 4575);
DISPLAY 0.978723 (225 4575);
PAINT WHITE (225 4575);
DISPLAY INVISIBLE (225 4575);
FORCEPROP 0 LAST $SEC 1
J 0
(225 4575);
DISPLAY 0.680851 (225 4575);
PAINT MONO (225 4575);
DISPLAY INVISIBLE (225 4575);
FORCEPROP 0 LAST CDS_SEC 1
J 0
(225 4575);
DISPLAY 1.021277 (225 4575);
DISPLAY INVISIBLE (225 4575);
FORCEADD OFFPAGE..2
(1000 4150);
FORCEPROP 2 LAST $XR0 182 
J 0
(1189 4150);
DISPLAY 0.638298 (1189 4150);
PAINT MONO (1189 4150);
FORCEPROP 2 LAST CDS_LIB standard
J 0
(1000 4150);
DISPLAY INVISIBLE (1000 4150);
FORCEPROP 1 LAST OFFPAGE TRUE
J 0
(1325 4025);
DISPLAY 0.872340 (1325 4025);
PAINT GREEN (1325 4025);
DISPLAY INVISIBLE (1325 4025);
FORCEPROP 1 LAST COMMENT_BODY TRUE
J 0
(955 4055);
DISPLAY 0.872340 (955 4055);
PAINT GREEN (955 4055);
DISPLAY INVISIBLE (955 4055);
FORCEPROP 2 LAST PATH I6
J 0
(1200 4200);
DISPLAY 1.021277 (1200 4200);
DISPLAY INVISIBLE (1200 4200);
FORCEADD QUANTA_TITLE_BLOCK_C..1
(5075 -800);
FORCEPROP 0 LAST CDS_CON_LAST_MODIFIED Fri Aug 25 14:03:19 2023
J 0
(3190 -785);
PAINT MONO (3190 -785);
DISPLAY INVISIBLE (3190 -785);
FORCEPROP 1 LAST CUSTOM_TXT_CDS <CON_LAST_MODIFIED>
J 0
(3190 -785);
DISPLAY 0.978723 (3190 -785);
FORCEPROP 2 LAST CUSTOM_TXT_CDS <XR_PAGE_TITLE>
J 0
(-2815 4450);
DISPLAY 0.638298 (-2815 4450);
PAINT PINK (-2815 4450);
DISPLAY INVISIBLE (-2815 4450);
FORCEPROP 1 LAST CUSTOM_TXT_CDS <NAME_2>
J 0
(1900 -750);
FORCEPROP 1 LAST CUSTOM_TXT_CDS <NAME_1>
J 0
(1900 -625);
FORCEPROP 1 LAST CUSTOM_TXT_CDS <Q_NUMBER>
J 0
(3672 -697);
DISPLAY 1.212766 (3672 -697);
FORCEPROP 1 LAST CUSTOM_TXT_CDS <Q_PROJ>
J 0
(2693 -698);
DISPLAY 1.212766 (2693 -698);
FORCEPROP 1 LAST CUSTOM_TXT_CDS <Q_REV>
J 0
(4891 -697);
DISPLAY 1.212766 (4891 -697);
FORCEPROP 1 LAST CUSTOM_TXT_CDS <CON_PAGE_NUM> OF <CON_TOTAL_PAGES>
J 0
(4629 -782);
DISPLAY 0.978723 (4629 -782);
FORCEPROP 1 LAST Q_TITLE PCH SIDEBAND - THERMTRIP & FIVRBREAK
J 0
(-4191 -749);
DISPLAY 2.446809 (-4191 -749);
PAINT GREEN (-4191 -749);
FORCEPROP 1 LAST Q_DEPT 
J 1
(1312 -751);
DISPLAY 1.957447 (1312 -751);
PAINT GREEN (1312 -751);
FORCEPROP 2 LAST CDS_XR_PAGE_TITLE CR-203 : @S9S_MB_2U_LIB.S9S_MB_2U(SCH_1):PAGE203
J 0
(-2815 4450);
DISPLAY 0.638298 (-2815 4450);
PAINT PINK (-2815 4450);
DISPLAY INVISIBLE (-2815 4450);
FORCEPROP 2 LAST CDS_LIB pure_quanta
J 0
(5075 -800);
PAINT MONO (5075 -800);
DISPLAY INVISIBLE (5075 -800);
FORCEPROP 1 LAST CDS_LMAN_SYM_OUTLINE -9475,6775,100,-125
J 0
(5075 -800);
DISPLAY 0.468085 (5075 -800);
PAINT GREEN (5075 -800);
DISPLAY INVISIBLE (5075 -800);
FORCEPROP 1 LAST COMMENT_BODY TRUE
J 0
(5087 -813);
DISPLAY 0.978723 (5087 -813);
PAINT GREEN (5087 -813);
DISPLAY INVISIBLE (5087 -813);
FORCEPROP 2 LAST PAGE_BORDER TRUE
J 0
(-2815 4450);
DISPLAY 0.638298 (-2815 4450);
PAINT PINK (-2815 4450);
DISPLAY INVISIBLE (-2815 4450);
WIRE 16 -1 (175 4600)(175 4500);
WIRE 16 -1 (-2775 3650)(-2775 3550);
WIRE 16 2175 (100 4575)(500 4575);
WIRE 16 2175 (500 4575)(500 4200);
WIRE 16 2175 (100 4575)(100 4200);
WIRE 16 2175 (100 4200)(500 4200);
WIRE 16 -1 (175 4150)(-1575 4150);
WIRE 16 -1 (175 4300)(175 4150);
WIRE 16 -1 (950 4150)(175 4150);
FORCEPROP 2 LAST SIG_NAME H_THERMTRIP_LVC1_N
J 0
(325 4160);
DISPLAY 0.553191 (325 4160);
PAINT WHITE (325 4160);
WIRE 16 273 (-3900 2600)(4750 2600);
WIRE 16 -1 (-300 3125)(-1650 3125);
FORCEPROP 2 LAST SIG_NAME FM_PCH_BMC_THERMTRIP_N
J 0
(-1210 3135);
DISPLAY 0.553191 (-1210 3135);
PAINT WHITE (-1210 3135);
WIRE 16 -1 (-1775 4150)(-2850 4150);
FORCEPROP 2 LAST SIG_NAME FM_THERMTRIP_DLY_LVC1_N
J 0
(-2760 4160);
DISPLAY 0.553191 (-2760 4160);
PAINT WHITE (-2760 4160);
WIRE 16 -1 (-2850 3125)(-2775 3125);
WIRE 16 -1 (-2775 3125)(-1850 3125);
FORCEPROP 2 LAST SIG_NAME FM_PLT_BMC_THERMTRIP_R_N
J 0
(-2710 3135);
DISPLAY 0.553191 (-2710 3135);
PAINT WHITE (-2710 3135);
WIRE 16 -1 (-2775 3350)(-2775 3125);
WIRE 16 -1 (-1775 975)(-2850 975);
FORCEPROP 2 LAST SIG_NAME FM_PCH_CPU_PWR_DEBUG_N
J 0
(-2760 985);
DISPLAY 0.553191 (-2760 985);
PAINT WHITE (-2760 985);
WIRE 16 -1 (950 975)(-1575 975);
FORCEPROP 2 LAST SIG_NAME FM_CPU_FBRK_DEBUG_N
J 0
(300 985);
DISPLAY 0.553191 (300 985);
PAINT WHITE (300 985);
DOT 1 (-2775 3125);
DOT 1 (175 4150);
FORCENOTE
20211130 CHANGE TO 75 OHM
(-325 4050) 0;
DISPLAY LEFT (-325 4050);
DISPLAY 1.021277 (-325 4050);
PAINT PINK (-325 4050);
QUIT
